#ISCELL
  mstr_misc dns *
  *
#ISCELL
  pure_quanta quanta_title_block_c *
  *
#ISCELL
  pure_quanta_power design_note *
  *
#CELL
  pure_quanta 9zxl0451ekilft *
  page111_i1
#ISCELL
  standard offpage *
  page111_i100
#ISCELL
  standard offpage *
  page111_i101
#ISCELL
  standard offpage *
  page111_i102
#ISCELL
  standard offpage *
  page111_i103
#ISCELL
  pure_quanta_power universal_power *
  page111_i104
#ISCELL
  pure_quanta_power universal_gnd *
  page111_i105
#CELL
  pure_quanta q_cap *
  page111_i106
#ISCELL
  pure_quanta_power universal_gnd *
  page111_i107
#ISCELL
  pure_quanta_power universal_gnd *
  page111_i109
#CELL
  pure_quanta q_cap *
  page111_i110
#CELL
  pure_quanta lsf0204drutr *
  page111_i111
#ISCELL
  standard offpage *
  page111_i112
#ISCELL
  standard offpage *
  page111_i113
#ISCELL
  standard offpage *
  page111_i114
#ISCELL
  standard offpage *
  page111_i115
#ISCELL
  pure_quanta_power universal_power *
  page111_i139
#CELL
  pure_quanta q_res *
  page111_i140
#CELL
  pure_quanta q_res *
  page111_i141
#CELL
  pure_quanta q_res *
  page111_i142
#CELL
  pure_quanta q_res *
  page111_i143
#ISCELL
  standard offpage *
  page111_i144
#ISCELL
  standard offpage *
  page111_i145
#ISCELL
  standard offpage *
  page111_i146
#ISCELL
  standard offpage *
  page111_i147
#ISCELL
  standard offpage *
  page111_i148
#ISCELL
  standard offpage *
  page111_i149
#ISCELL
  standard offpage *
  page111_i150
#ISCELL
  standard offpage *
  page111_i151
#CELL
  pure_quanta q_res *
  page111_i152
#CELL
  pure_quanta q_res *
  page111_i153
#CELL
  pure_quanta q_res *
  page111_i154
#CELL
  pure_quanta q_res *
  page111_i155
#ISCELL
  standard offpage *
  page111_i161
#CELL
  pure_quanta q_res *
  page111_i162
#ISCELL
  pure_quanta_power universal_gnd *
  page111_i166
#CELL
  pure_quanta q_res *
  page111_i167
#ISCELL
  standard offpage *
  page111_i170
#ISCELL
  standard offpage *
  page111_i171
#CELL
  pure_quanta q_res *
  page111_i174
#ISCELL
  pure_quanta_power universal_power *
  page111_i175
#ISCELL
  pure_quanta_power universal_gnd *
  page111_i176
#ISCELL
  standard offpage *
  page111_i177
#CELL
  pure_quanta q_res *
  page111_i178
#CELL
  pure_quanta q_res *
  page111_i179
#CELL
  pure_quanta q_res *
  page111_i181
#CELL
  pure_quanta q_res *
  page111_i182
#ISCELL
  pure_quanta_power vcc_core *
  page111_i183
#ISCELL
  pure_quanta_power vcc_core *
  page111_i184
#CELL
  pure_quanta q_res *
  page111_i187
#ISCELL
  pure_quanta_power universal_gnd *
  page111_i188
#CELL
  pure_quanta mosfet_n_gsd *
  page111_i189
#ISCELL
  standard offpage *
  page111_i190
#ISCELL
  pure_quanta_power vcc_core *
  page111_i191
#ISCELL
  standard offpage *
  page111_i192
#CELL
  pure_quanta q_res *
  page111_i193
#ISCELL
  standard offpage *
  page111_i194
#ISCELL
  pure_quanta_power vcc_core *
  page111_i2
#ISCELL
  pure_quanta_power universal_power *
  page111_i3
#ISCELL
  standard offpage *
  page111_i38
#ISCELL
  standard offpage *
  page111_i39
#ISCELL
  pure_quanta_power vcc_core *
  page111_i4
#ISCELL
  mstr_symbols vcc_core *
  page111_i40
#CELL
  pure_quanta q_cap *
  page111_i41
#CELL
  pure_quanta q_cap *
  page111_i42
#CELL
  pure_quanta q_cap *
  page111_i43
#CELL
  pure_quanta q_res *
  page111_i44
#ISCELL
  pure_quanta_power universal_gnd *
  page111_i45
#ISCELL
  pure_quanta_power universal_gnd *
  page111_i46
#ISCELL
  pure_quanta_power universal_gnd *
  page111_i47
#CELL
  pure_quanta q_cap *
  page111_i49
#ISCELL
  pure_quanta_power universal_gnd *
  page111_i51
#ISCELL
  mstr_symbols universal_power *
  page111_i52
#ISCELL
  pure_quanta_power universal_power *
  page111_i57
#CELL
  pure_quanta q_inductor *
  page111_i58
#CELL
  pure_quanta q_cap *
  page111_i59
#CELL
  pure_quanta q_cap *
  page111_i61
#ISCELL
  pure_quanta_power universal_gnd *
  page111_i62
#ISCELL
  pure_quanta_power universal_gnd *
  page111_i63
#CELL
  pure_quanta q_cap *
  page111_i65
#CELL
  pure_quanta q_cap *
  page111_i67
#ISCELL
  pure_quanta_power universal_gnd *
  page111_i68
#ISCELL
  pure_quanta_power universal_gnd *
  page111_i69
#CELL
  pure_quanta q_cap *
  page111_i71
#ISCELL
  pure_quanta_power universal_gnd *
  page111_i72
#ISCELL
  standard offpage *
  page111_i73
#ISCELL
  standard offpage *
  page111_i74
#ISCELL
  standard offpage *
  page111_i75
#ISCELL
  standard offpage *
  page111_i76
#CELL
  pure_quanta q_res *
  page111_i79
#CELL
  pure_quanta q_res *
  page111_i80
#CELL
  pure_quanta q_res *
  page111_i81
#CELL
  pure_quanta q_res *
  page111_i82
#ISCELL
  pure_quanta_power universal_gnd *
  page111_i85
#ISCELL
  pure_quanta_power universal_power *
  page111_i86
#CELL
  pure_quanta q_res *
  page111_i87
#CELL
  pure_quanta q_res *
  page111_i88
#ISCELL
  pure_quanta_power universal_gnd *
  page111_i89
#ISCELL
  pure_quanta_power universal_gnd *
  page111_i90
#ISCELL
  pure_quanta_power universal_power *
  page111_i91
#CELL
  pure_quanta q_res *
  page111_i92
#CELL
  pure_quanta q_res *
  page111_i93
#ISCELL
  standard offpage *
  page111_i94
#ISCELL
  standard offpage *
  page111_i95
#ISCELL
  standard offpage *
  page111_i96
#CELL
  pure_quanta q_res *
  page111_i97
#CELL
  pure_quanta q_res *
  page111_i98
#ISCELL
  standard offpage *
  page111_i99
